(kicad_pcb
	(version 20260206)
	(generator "pcbnew")
	(generator_version "10.0")
	(general
		(thickness 1.6)
		(legacy_teardrops no)
	)
	(paper "A4")
	(title_block
		(title "12092022_DA0F0TMDCD0_F0T_Management_Board_D_brd_V3_OCP.brd")
		(comment 1 "Grand Teton / footprints 378-382 of 1440")
	)
	(layers
		(0 "F.Cu" signal "TOP")
		(4 "In1.Cu" signal "GND")
		(6 "In2.Cu" signal "IN1")
		(8 "In3.Cu" signal "GND1")
		(10 "In4.Cu" signal "IN2")
		(12 "In5.Cu" signal "VCC")
		(14 "In6.Cu" signal "VCC1")
		(16 "In7.Cu" signal "IN3")
		(18 "In8.Cu" signal "GND2")
		(20 "In9.Cu" signal "IN4")
		(22 "In10.Cu" signal "GND3")
		(2 "B.Cu" signal "BOTTOM")
		(9 "F.Adhes" user "F.Adhesive")
		(11 "B.Adhes" user "B.Adhesive")
		(13 "F.Paste" user "Package Geometry/Pastemask Top")
		(15 "B.Paste" user "Package Geometry/Pastemask Bottom")
		(5 "F.SilkS" user "Ref Des/Silkscreen Top")
		(7 "B.SilkS" user "Ref Des/Silkscreen Bottom")
		(1 "F.Mask" user "Board Geometry/Soldermask Top")
		(3 "B.Mask" user "Board Geometry/Soldermask Bottom")
		(17 "Dwgs.User" user "User.Drawings")
		(19 "Cmts.User" user "User.Comments")
		(21 "Eco1.User" user "User.Eco1")
		(23 "Eco2.User" user "User.Eco2")
		(25 "Edge.Cuts" user "Board Geometry/Outline")
		(27 "Margin" user)
		(31 "F.CrtYd" user "Package Geometry/Place Bound Top")
		(29 "B.CrtYd" user "Package Geometry/Place Bound Bottom")
		(35 "F.Fab" user "Ref Des/Assembly Top")
		(33 "B.Fab" user "Ref Des/Assembly Bottom")
	)
	(footprint ""
		(layer "F.Cu")
		(at 62.701932 -94.856046 180)
		(property "Reference" "J5"
			(at -3.414268 -4.217416 0)
			(unlocked yes)
			(layer "F.SilkS")
			(effects
				(font
					(size 0.7874 0.5842)
					(thickness 0.1524)
				)
				(justify left)
			)
		)
		(property "Value" ""
			(at 0 0 180)
			(layer "F.Fab")
			(effects
				(font
					(size 1.27 1.27)
				)
			)
		)
		(duplicate_pad_numbers_are_jumpers no)
		(fp_line
			(start 2.500122 5.150104)
			(end -2.500122 5.150104)
			(stroke
				(width 0.1524)
				(type default)
			)
			(layer "F.SilkS")
		)
		(fp_line
			(start 2.500122 5.08)
			(end 2.500122 5.150104)
			(stroke
				(width 0.1524)
				(type default)
			)
			(layer "F.SilkS")
		)
		(fp_line
			(start 2.500122 2.4384)
			(end 2.500122 3.3782)
			(stroke
				(width 0.1524)
				(type default)
			)
			(layer "F.SilkS")
		)
		(fp_line
			(start 2.500122 -3.3782)
			(end 2.500122 -2.4384)
			(stroke
				(width 0.1524)
				(type default)
			)
			(layer "F.SilkS")
		)
		(fp_line
			(start 2.500122 -5.150104)
			(end 2.500122 -5.08)
			(stroke
				(width 0.1524)
				(type default)
			)
			(layer "F.SilkS")
		)
		(fp_line
			(start -2.500122 5.150104)
			(end -2.500122 5.08)
			(stroke
				(width 0.1524)
				(type default)
			)
			(layer "F.SilkS")
		)
		(fp_line
			(start -2.500122 3.3782)
			(end -2.500122 2.9464)
			(stroke
				(width 0.1524)
				(type default)
			)
			(layer "F.SilkS")
		)
		(fp_line
			(start -2.500122 -2.9464)
			(end -2.500122 -3.3782)
			(stroke
				(width 0.1524)
				(type default)
			)
			(layer "F.SilkS")
		)
		(fp_line
			(start -2.500122 -5.08)
			(end -2.500122 -5.150104)
			(stroke
				(width 0.1524)
				(type default)
			)
			(layer "F.SilkS")
		)
		(fp_line
			(start -2.500122 -5.150104)
			(end 2.500122 -5.150104)
			(stroke
				(width 0.1524)
				(type default)
			)
			(layer "F.SilkS")
		)
		(fp_poly
			(pts
				(xy -4.0894 -1.992122) (xy -4.0894 -3.008122) (xy -3.0734 -2.500122)
			)
			(stroke
				(width 0)
				(type default)
			)
			(fill yes)
			(layer "F.SilkS")
		)
		(fp_line
			(start 2.500122 5.150104)
			(end 2.500122 -5.150104)
			(stroke
				(width 0.1)
				(type default)
			)
			(layer "F.Fab")
		)
		(fp_line
			(start 2.500122 -5.150104)
			(end -2.500122 -5.150104)
			(stroke
				(width 0.1)
				(type default)
			)
			(layer "F.Fab")
		)
		(fp_line
			(start -2.500122 5.150104)
			(end 2.500122 5.150104)
			(stroke
				(width 0.1)
				(type default)
			)
			(layer "F.Fab")
		)
		(fp_line
			(start -2.500122 -5.150104)
			(end -2.500122 5.150104)
			(stroke
				(width 0.1)
				(type default)
			)
			(layer "F.Fab")
		)
		(fp_poly
			(pts
				(xy -4.0894 -1.992122) (xy -4.0894 -3.008122) (xy -3.0734 -2.500122)
			)
			(stroke
				(width 0)
				(type default)
			)
			(fill yes)
			(layer "F.Fab")
		)
		(fp_text user "11"
			(at 4.002532 3.224784 0)
			(unlocked yes)
			(layer "F.SilkS")
			(effects
				(font
					(size 0.7874 0.5842)
					(thickness 0.1524)
				)
			)
		)
		(fp_text user "7"
			(at 3.646932 -2.134616 0)
			(unlocked yes)
			(layer "F.SilkS")
			(effects
				(font
					(size 0.7874 0.5842)
					(thickness 0.1524)
				)
			)
		)
		(fp_text user "6"
			(at -3.592068 2.668524 180)
			(unlocked yes)
			(layer "F.SilkS")
			(effects
				(font
					(size 0.7874 0.5842)
					(thickness 0.1524)
				)
			)
		)
		(fp_text user "7"
			(at 3.520948 -2.048002 90)
			(unlocked yes)
			(layer "F.Fab")
			(effects
				(font
					(size 0.7874 0.5842)
					(thickness 0.1524)
				)
			)
		)
		(fp_text user "11"
			(at 3.495548 2.028444 90)
			(unlocked yes)
			(layer "F.Fab")
			(effects
				(font
					(size 0.7874 0.5842)
					(thickness 0.1524)
				)
			)
		)
		(fp_text user "6"
			(at -3.591052 2.574798 90)
			(unlocked yes)
			(layer "F.Fab")
			(effects
				(font
					(size 0.7874 0.5842)
					(thickness 0.1524)
				)
			)
		)
		(pad "1" smd rect
			(at -2.109978 -2.500122 270)
			(size 0.6096 1.651)
			(layers "F.Cu" "F.Mask" "F.Paste")
			(net "SPI_SYS_R1_CLK")
		)
		(pad "2" smd rect
			(at -2.109978 -1.500124 270)
			(size 0.6096 1.651)
			(layers "F.Cu" "F.Mask" "F.Paste")
			(net "RST_PLTRST_TPM_N")
		)
		(pad "3" smd rect
			(at -2.109978 -0.499872 270)
			(size 0.6096 1.651)
			(layers "F.Cu" "F.Mask" "F.Paste")
			(net "SPI_SYS_R1_MOSI")
		)
		(pad "4" smd rect
			(at -2.109978 0.499872 270)
			(size 0.6096 1.651)
			(layers "F.Cu" "F.Mask" "F.Paste")
			(net "SPI_SYS_R1_MISO")
		)
		(pad "5" smd rect
			(at -2.109978 1.500124 270)
			(size 0.6096 1.651)
			(layers "F.Cu" "F.Mask" "F.Paste")
			(net "SPI_TPM_CS_N_R")
		)
		(pad "6" smd rect
			(at -2.109978 2.500122 270)
			(size 0.6096 1.651)
			(layers "F.Cu" "F.Mask" "F.Paste")
			(net "SMB_PCH_TPM_SDA")
		)
		(pad "7" smd rect
			(at 2.109978 -1.999996 90)
			(size 0.6096 1.651)
			(layers "F.Cu" "F.Mask" "F.Paste")
			(net "P3V3_AUX")
		)
		(pad "8" smd rect
			(at 2.109978 -0.999998 90)
			(size 0.6096 1.651)
			(layers "F.Cu" "F.Mask" "F.Paste")
			(net "FM_TPM_PRSNT_0_N")
		)
		(pad "9" smd rect
			(at 2.109978 0 90)
			(size 0.6096 1.651)
			(layers "F.Cu" "F.Mask" "F.Paste")
			(net "IRQ_PCH_TPM_SPI_R_N")
		)
		(pad "10" smd rect
			(at 2.109978 0.999998 90)
			(size 0.6096 1.651)
			(layers "F.Cu" "F.Mask" "F.Paste")
			(net "SMB_PCH_TPM_SCL")
		)
		(pad "11" smd rect
			(at 2.109978 1.999996 90)
			(size 0.6096 1.651)
			(layers "F.Cu" "F.Mask" "F.Paste")
			(net "GND")
		)
		(pad "G1" smd rect
			(at 0 -4.219956 270)
			(size 1.4224 5.8674)
			(layers "F.Cu" "F.Mask" "F.Paste")
			(net "GND")
		)
		(pad "G2" smd rect
			(at 0 4.219956 90)
			(size 1.4224 5.8674)
			(layers "F.Cu" "F.Mask" "F.Paste")
			(net "GND")
		)
	)
	(footprint ""
		(layer "F.Cu")
		(at 9.2202 -67.183 180)
		(property "Reference" "R415"
			(at 0 0 180)
			(layer "F.SilkS")
			(hide yes)
			(effects
				(font
					(size 1.27 1.27)
				)
			)
		)
		(property "Value" ""
			(at 0 0 180)
			(layer "F.Fab")
			(effects
				(font
					(size 1.27 1.27)
				)
			)
		)
		(duplicate_pad_numbers_are_jumpers no)
		(fp_line
			(start 0.7874 0.4064)
			(end -0.7874 0.4064)
			(stroke
				(width 0.1524)
				(type default)
			)
			(layer "F.SilkS")
		)
		(fp_line
			(start 0.7874 -0.4064)
			(end 0.7874 0.4064)
			(stroke
				(width 0.1524)
				(type default)
			)
			(layer "F.SilkS")
		)
		(fp_line
			(start -0.7874 0.4064)
			(end -0.7874 -0.4064)
			(stroke
				(width 0.1524)
				(type default)
			)
			(layer "F.SilkS")
		)
		(fp_line
			(start -0.7874 -0.4064)
			(end 0.7874 -0.4064)
			(stroke
				(width 0.1524)
				(type default)
			)
			(layer "F.SilkS")
		)
		(fp_line
			(start 0.67945 0.3048)
			(end 0.120396 0.3048)
			(stroke
				(width 0.1)
				(type default)
			)
			(layer "F.Fab")
		)
		(fp_line
			(start 0.67945 -0.3048)
			(end 0.67945 0.3048)
			(stroke
				(width 0.1)
				(type default)
			)
			(layer "F.Fab")
		)
		(fp_line
			(start 0.12065 -0.2794)
			(end 0.12065 -0.3048)
			(stroke
				(width 0.1)
				(type default)
			)
			(layer "F.Fab")
		)
		(fp_line
			(start 0.12065 -0.3048)
			(end 0.67945 -0.3048)
			(stroke
				(width 0.1)
				(type default)
			)
			(layer "F.Fab")
		)
		(fp_line
			(start 0.120396 0.3048)
			(end 0.120396 0.2794)
			(stroke
				(width 0.1)
				(type default)
			)
			(layer "F.Fab")
		)
		(fp_line
			(start 0.120396 0.2794)
			(end -0.12065 0.2794)
			(stroke
				(width 0.1)
				(type default)
			)
			(layer "F.Fab")
		)
		(fp_line
			(start -0.12065 0.3048)
			(end -0.67945 0.3048)
			(stroke
				(width 0.1)
				(type default)
			)
			(layer "F.Fab")
		)
		(fp_line
			(start -0.12065 0.2794)
			(end -0.12065 0.3048)
			(stroke
				(width 0.1)
				(type default)
			)
			(layer "F.Fab")
		)
		(fp_line
			(start -0.12065 -0.2794)
			(end 0.12065 -0.2794)
			(stroke
				(width 0.1)
				(type default)
			)
			(layer "F.Fab")
		)
		(fp_line
			(start -0.12065 -0.305054)
			(end -0.12065 -0.2794)
			(stroke
				(width 0.1)
				(type default)
			)
			(layer "F.Fab")
		)
		(fp_line
			(start -0.67945 0.3048)
			(end -0.67945 -0.305054)
			(stroke
				(width 0.1)
				(type default)
			)
			(layer "F.Fab")
		)
		(fp_line
			(start -0.67945 -0.305054)
			(end -0.12065 -0.305054)
			(stroke
				(width 0.1)
				(type default)
			)
			(layer "F.Fab")
		)
		(pad "1" smd circle
			(at -0.40005 0 180)
			(size 0 0)
			(layers "F.Cu" "F.Mask" "F.Paste")
			(net "SW_P3V3_AUX_BST_R")
		)
		(pad "2" smd circle
			(at 0.40005 0 180)
			(size 0 0)
			(layers "F.Cu" "F.Mask" "F.Paste")
			(net "SW_P3V3_AUX_BST")
		)
	)
	(footprint ""
		(layer "F.Cu")
		(at 70.370446 -33.033716 90)
		(property "Reference" "C251"
			(at 0 0 90)
			(layer "F.SilkS")
			(hide yes)
			(effects
				(font
					(size 1.27 1.27)
				)
			)
		)
		(property "Value" ""
			(at 0 0 90)
			(layer "F.Fab")
			(effects
				(font
					(size 1.27 1.27)
				)
			)
		)
		(duplicate_pad_numbers_are_jumpers no)
		(fp_line
			(start 0.7874 -0.4064)
			(end 0.7874 0.4064)
			(stroke
				(width 0.1524)
				(type default)
			)
			(layer "F.SilkS")
		)
		(fp_line
			(start -0.7874 -0.4064)
			(end 0.7874 -0.4064)
			(stroke
				(width 0.1524)
				(type default)
			)
			(layer "F.SilkS")
		)
		(fp_line
			(start 0.7874 0.4064)
			(end -0.7874 0.4064)
			(stroke
				(width 0.1524)
				(type default)
			)
			(layer "F.SilkS")
		)
		(fp_line
			(start -0.7874 0.4064)
			(end -0.7874 -0.4064)
			(stroke
				(width 0.1524)
				(type default)
			)
			(layer "F.SilkS")
		)
		(fp_line
			(start -0.12065 -0.305054)
			(end -0.12065 -0.2794)
			(stroke
				(width 0.1)
				(type default)
			)
			(layer "F.Fab")
		)
		(fp_line
			(start -0.67945 -0.305054)
			(end -0.12065 -0.305054)
			(stroke
				(width 0.1)
				(type default)
			)
			(layer "F.Fab")
		)
		(fp_line
			(start 0.67945 -0.3048)
			(end 0.67945 0.3048)
			(stroke
				(width 0.1)
				(type default)
			)
			(layer "F.Fab")
		)
		(fp_line
			(start 0.12065 -0.3048)
			(end 0.67945 -0.3048)
			(stroke
				(width 0.1)
				(type default)
			)
			(layer "F.Fab")
		)
		(fp_line
			(start 0.12065 -0.2794)
			(end 0.12065 -0.3048)
			(stroke
				(width 0.1)
				(type default)
			)
			(layer "F.Fab")
		)
		(fp_line
			(start -0.12065 -0.2794)
			(end 0.12065 -0.2794)
			(stroke
				(width 0.1)
				(type default)
			)
			(layer "F.Fab")
		)
		(fp_line
			(start 0.120396 0.2794)
			(end -0.12065 0.2794)
			(stroke
				(width 0.1)
				(type default)
			)
			(layer "F.Fab")
		)
		(fp_line
			(start -0.12065 0.2794)
			(end -0.12065 0.3048)
			(stroke
				(width 0.1)
				(type default)
			)
			(layer "F.Fab")
		)
		(fp_line
			(start 0.67945 0.3048)
			(end 0.120396 0.3048)
			(stroke
				(width 0.1)
				(type default)
			)
			(layer "F.Fab")
		)
		(fp_line
			(start 0.120396 0.3048)
			(end 0.120396 0.2794)
			(stroke
				(width 0.1)
				(type default)
			)
			(layer "F.Fab")
		)
		(fp_line
			(start -0.12065 0.3048)
			(end -0.67945 0.3048)
			(stroke
				(width 0.1)
				(type default)
			)
			(layer "F.Fab")
		)
		(fp_line
			(start -0.67945 0.3048)
			(end -0.67945 -0.305054)
			(stroke
				(width 0.1)
				(type default)
			)
			(layer "F.Fab")
		)
		(pad "1" smd circle
			(at -0.40005 0 90)
			(size 0 0)
			(layers "F.Cu" "F.Mask" "F.Paste")
			(net "P3V3_RGM")
		)
		(pad "2" smd circle
			(at 0.40005 0 90)
			(size 0 0)
			(layers "F.Cu" "F.Mask" "F.Paste")
			(net "GND")
		)
	)
	(footprint ""
		(layer "F.Cu")
		(at 29.2608 -28.5242)
		(property "Reference" "L28"
			(at 0 0 0)
			(layer "F.SilkS")
			(hide yes)
			(effects
				(font
					(size 1.27 1.27)
				)
			)
		)
		(property "Value" ""
			(at 0 0 0)
			(layer "F.Fab")
			(effects
				(font
					(size 1.27 1.27)
				)
			)
		)
		(duplicate_pad_numbers_are_jumpers no)
		(fp_line
			(start -1.27 -0.5842)
			(end 1.27 -0.5842)
			(stroke
				(width 0.1524)
				(type default)
			)
			(layer "F.SilkS")
		)
		(fp_line
			(start -1.27 -0.5588)
			(end -1.27 -0.5842)
			(stroke
				(width 0.1524)
				(type default)
			)
			(layer "F.SilkS")
		)
		(fp_line
			(start -1.27 0.5842)
			(end -1.27 -0.5842)
			(stroke
				(width 0.1524)
				(type default)
			)
			(layer "F.SilkS")
		)
		(fp_line
			(start -0.127 0.5842)
			(end -0.127 -0.5842)
			(stroke
				(width 0.1524)
				(type default)
			)
			(layer "F.SilkS")
		)
		(fp_line
			(start 0.127 0.5842)
			(end 0.127 -0.5842)
			(stroke
				(width 0.1524)
				(type default)
			)
			(layer "F.SilkS")
		)
		(fp_line
			(start 1.27 0.5842)
			(end -1.27 0.5842)
			(stroke
				(width 0.1524)
				(type default)
			)
			(layer "F.SilkS")
		)
		(fp_line
			(start 1.27 0.5842)
			(end 1.27 -0.5842)
			(stroke
				(width 0.1524)
				(type default)
			)
			(layer "F.SilkS")
		)
		(fp_line
			(start -1.194308 -0.406654)
			(end -0.9144 -0.406654)
			(stroke
				(width 0.1)
				(type default)
			)
			(layer "F.Fab")
		)
		(fp_line
			(start -1.194308 0.406654)
			(end -1.194308 -0.406654)
			(stroke
				(width 0.1)
				(type default)
			)
			(layer "F.Fab")
		)
		(fp_line
			(start -0.9144 -0.508)
			(end 0.9144 -0.508)
			(stroke
				(width 0.1)
				(type default)
			)
			(layer "F.Fab")
		)
		(fp_line
			(start -0.9144 -0.406654)
			(end -0.9144 -0.508)
			(stroke
				(width 0.1)
				(type default)
			)
			(layer "F.Fab")
		)
		(fp_line
			(start -0.9144 0.406654)
			(end -1.194308 0.406654)
			(stroke
				(width 0.1)
				(type default)
			)
			(layer "F.Fab")
		)
		(fp_line
			(start -0.9144 0.508)
			(end -0.9144 0.406654)
			(stroke
				(width 0.1)
				(type default)
			)
			(layer "F.Fab")
		)
		(fp_line
			(start 0.9144 -0.508)
			(end 0.9144 -0.406654)
			(stroke
				(width 0.1)
				(type default)
			)
			(layer "F.Fab")
		)
		(fp_line
			(start 0.9144 -0.406654)
			(end 1.1938 -0.406654)
			(stroke
				(width 0.1)
				(type default)
			)
			(layer "F.Fab")
		)
		(fp_line
			(start 0.9144 0.4064)
			(end 0.9144 0.508)
			(stroke
				(width 0.1)
				(type default)
			)
			(layer "F.Fab")
		)
		(fp_line
			(start 0.9144 0.508)
			(end -0.9144 0.508)
			(stroke
				(width 0.1)
				(type default)
			)
			(layer "F.Fab")
		)
		(fp_line
			(start 1.1938 -0.406654)
			(end 1.1938 0.4064)
			(stroke
				(width 0.1)
				(type default)
			)
			(layer "F.Fab")
		)
		(fp_line
			(start 1.1938 0.4064)
			(end 0.9144 0.4064)
			(stroke
				(width 0.1)
				(type default)
			)
			(layer "F.Fab")
		)
		(pad "1" smd rect
			(at -0.7366 0 270)
			(size 0.7112 0.8128)
			(layers "F.Cu" "F.Mask" "F.Paste")
			(net "V_DACB")
		)
		(pad "2" smd rect
			(at 0.7366 0 270)
			(size 0.7112 0.8128)
			(layers "F.Cu" "F.Mask" "F.Paste")
			(net "V_DACB_IO")
		)
	)
	(footprint ""
		(layer "F.Cu")
		(at 35.052 -53.213 -90)
		(property "Reference" "C292"
			(at 0 0 270)
			(layer "F.SilkS")
			(hide yes)
			(effects
				(font
					(size 1.27 1.27)
				)
			)
		)
		(property "Value" ""
			(at 0 0 270)
			(layer "F.Fab")
			(effects
				(font
					(size 1.27 1.27)
				)
			)
		)
		(duplicate_pad_numbers_are_jumpers no)
		(fp_line
			(start -0.7874 0.4064)
			(end -0.7874 -0.4064)
			(stroke
				(width 0.1524)
				(type default)
			)
			(layer "F.SilkS")
		)
		(fp_line
			(start 0.7874 0.4064)
			(end -0.7874 0.4064)
			(stroke
				(width 0.1524)
				(type default)
			)
			(layer "F.SilkS")
		)
		(fp_line
			(start -0.7874 -0.4064)
			(end 0.7874 -0.4064)
			(stroke
				(width 0.1524)
				(type default)
			)
			(layer "F.SilkS")
		)
		(fp_line
			(start 0.7874 -0.4064)
			(end 0.7874 0.4064)
			(stroke
				(width 0.1524)
				(type default)
			)
			(layer "F.SilkS")
		)
		(fp_line
			(start -0.67945 0.3048)
			(end -0.67945 -0.305054)
			(stroke
				(width 0.1)
				(type default)
			)
			(layer "F.Fab")
		)
		(fp_line
			(start -0.12065 0.3048)
			(end -0.67945 0.3048)
			(stroke
				(width 0.1)
				(type default)
			)
			(layer "F.Fab")
		)
		(fp_line
			(start 0.120396 0.3048)
			(end 0.120396 0.2794)
			(stroke
				(width 0.1)
				(type default)
			)
			(layer "F.Fab")
		)
		(fp_line
			(start 0.67945 0.3048)
			(end 0.120396 0.3048)
			(stroke
				(width 0.1)
				(type default)
			)
			(layer "F.Fab")
		)
		(fp_line
			(start -0.12065 0.2794)
			(end -0.12065 0.3048)
			(stroke
				(width 0.1)
				(type default)
			)
			(layer "F.Fab")
		)
		(fp_line
			(start 0.120396 0.2794)
			(end -0.12065 0.2794)
			(stroke
				(width 0.1)
				(type default)
			)
			(layer "F.Fab")
		)
		(fp_line
			(start -0.12065 -0.2794)
			(end 0.12065 -0.2794)
			(stroke
				(width 0.1)
				(type default)
			)
			(layer "F.Fab")
		)
		(fp_line
			(start 0.12065 -0.2794)
			(end 0.12065 -0.3048)
			(stroke
				(width 0.1)
				(type default)
			)
			(layer "F.Fab")
		)
		(fp_line
			(start 0.12065 -0.3048)
			(end 0.67945 -0.3048)
			(stroke
				(width 0.1)
				(type default)
			)
			(layer "F.Fab")
		)
		(fp_line
			(start 0.67945 -0.3048)
			(end 0.67945 0.3048)
			(stroke
				(width 0.1)
				(type default)
			)
			(layer "F.Fab")
		)
		(fp_line
			(start -0.67945 -0.305054)
			(end -0.12065 -0.305054)
			(stroke
				(width 0.1)
				(type default)
			)
			(layer "F.Fab")
		)
		(fp_line
			(start -0.12065 -0.305054)
			(end -0.12065 -0.2794)
			(stroke
				(width 0.1)
				(type default)
			)
			(layer "F.Fab")
		)
		(pad "1" smd circle
			(at -0.40005 0 270)
			(size 0 0)
			(layers "F.Cu" "F.Mask" "F.Paste")
			(net "P5V_AUX")
		)
		(pad "2" smd circle
			(at 0.40005 0 270)
			(size 0 0)
			(layers "F.Cu" "F.Mask" "F.Paste")
			(net "GND")
		)
	)
)
